# TIMECARD (Time Appliance Project (Time Card)) — schematic netlist excerpt (pin names and nets, part order shuffled) for the footprints in the layout excerpt that follows; sources: Cadence DE-HDL packaged netlist, KiCad conversion of R4006-B0001-02_R01.brd

C285  CAPACITOR  0.1UF 10V 10%  pkg SMC_0402R_H022  page 20 : \1\ = UNNAMED_9_BNO080LGA28_I29_CAP ; \2\ = SG
R21  RESISTOR  4.7KOHM 1%  pkg SMC_0402R_H016  page 17 : \1\ = XP3R3V_FPGA ; \2\ = LM75B_I2C_SCL

(kicad_pcb
	(version 20260206)
	(generator "pcbnew")
	(generator_version "10.0")
	(general
		(thickness 1.6)
		(legacy_teardrops no)
	)
	(paper "A4")
	(title_block
		(title "timecard-production-celestica-r4006 — R4006-B0001-02_R01.brd")
		(comment 1 "Time Appliance Project (Time Card) / footprints 447-448 of 1113")
	)
	(layers
		(0 "F.Cu" signal "TOP")
		(4 "In1.Cu" signal "L02_GND1")
		(6 "In2.Cu" signal "L03_SIG1")
		(8 "In3.Cu" signal "L04_GND2")
		(10 "In4.Cu" signal "L05_VCC1")
		(12 "In5.Cu" signal "L06_VCC2")
		(14 "In6.Cu" signal "L07_GND3")
		(16 "In7.Cu" signal "L08_SIG2")
		(18 "In8.Cu" signal "L09_GND4")
		(2 "B.Cu" signal "BOTTOM")
		(9 "F.Adhes" user "F.Adhesive")
		(11 "B.Adhes" user "B.Adhesive")
		(13 "F.Paste" user "Package Geometry/Pastemask Top")
		(15 "B.Paste" user "Package Geometry/Pastemask Bottom")
		(5 "F.SilkS" user "Ref Des/Silkscreen Top")
		(7 "B.SilkS" user "Ref Des/Silkscreen Bottom")
		(1 "F.Mask" user "Board Geometry/Soldermask Top")
		(3 "B.Mask" user "Board Geometry/Soldermask Bottom")
		(17 "Dwgs.User" user "User.Drawings")
		(19 "Cmts.User" user "User.Comments")
		(21 "Eco1.User" user "User.Eco1")
		(23 "Eco2.User" user "User.Eco2")
		(25 "Edge.Cuts" user "Board Geometry/Outline")
		(27 "Margin" user)
		(31 "F.CrtYd" user "Package Geometry/Place Bound Top")
		(29 "B.CrtYd" user "Package Geometry/Place Bound Bottom")
		(35 "F.Fab" user "Ref Des/Assembly Top")
		(33 "B.Fab" user "Ref Des/Assembly Bottom")
	)
	(footprint ""
		(layer "F.Cu")
		(at 150.749 -26.035)
		(property "Reference" "R21"
			(at -0.381 2.83337 0)
			(unlocked yes)
			(layer "F.SilkS")
			(effects
				(font
					(size 0.7874 0.5842)
					(thickness 0.1524)
				)
			)
		)
		(property "Value" "VAL*"
			(at 0.02032 2.13233 0)
			(unlocked yes)
			(layer "F.Fab")
			(hide yes)
			(effects
				(font
					(size 0.7874 0.5842)
					(thickness 0.1524)
				)
			)
		)
		(property "Tolerance" "TOL*"
			(at 0.044704 3.05435 0)
			(unlocked yes)
			(layer "Cmts.User")
			(hide yes)
			(effects
				(font
					(size 0.7874 0.5842)
					(thickness 0.1524)
				)
			)
		)
		(property "User Part Number" "PARTNUM*"
			(at 0.02032 4.024884 0)
			(unlocked yes)
			(layer "Cmts.User")
			(hide yes)
			(effects
				(font
					(size 0.7874 0.5842)
					(thickness 0.1524)
				)
			)
		)
		(property "Device Type" "RESISTOR-G155-14701-01,4.7KOHMA"
			(at 0.008382 1.210564 0)
			(unlocked yes)
			(layer "F.Fab")
			(hide yes)
			(effects
				(font
					(size 0.7874 0.5842)
					(thickness 0.1524)
				)
			)
		)
		(duplicate_pad_numbers_are_jumpers no)
		(fp_line
			(start -1.143 -0.5588)
			(end -1.143 0.5588)
			(stroke
				(width 0.1)
				(type default)
			)
			(layer "F.SilkS")
		)
		(fp_line
			(start -1.143 0.5588)
			(end 1.143 0.5588)
			(stroke
				(width 0.1)
				(type default)
			)
			(layer "F.SilkS")
		)
		(fp_line
			(start 1.143 -0.5588)
			(end -1.143 -0.5588)
			(stroke
				(width 0.1)
				(type default)
			)
			(layer "F.SilkS")
		)
		(fp_line
			(start 1.143 0.5588)
			(end 1.143 -0.5588)
			(stroke
				(width 0.1)
				(type default)
			)
			(layer "F.SilkS")
		)
		(fp_rect
			(start -1.143 -0.5588)
			(end 1.143 0.5588)
			(stroke
				(width 0)
				(type default)
			)
			(fill no)
			(layer "F.CrtYd")
		)
		(fp_line
			(start -0.508 -0.3048)
			(end -0.508 0.3048)
			(stroke
				(width 0.1)
				(type default)
			)
			(layer "F.Fab")
		)
		(fp_line
			(start -0.508 0.3048)
			(end 0.508 0.3048)
			(stroke
				(width 0.1)
				(type default)
			)
			(layer "F.Fab")
		)
		(fp_line
			(start 0.508 -0.3048)
			(end -0.508 -0.3048)
			(stroke
				(width 0.1)
				(type default)
			)
			(layer "F.Fab")
		)
		(fp_line
			(start 0.508 0.3048)
			(end 0.508 -0.3048)
			(stroke
				(width 0.1)
				(type default)
			)
			(layer "F.Fab")
		)
		(pad "1" smd rect
			(at -0.5334 0)
			(size 0.7112 0.6096)
			(layers "F.Cu" "F.Mask" "F.Paste")
			(net "XP3R3V_FPGA")
		)
		(pad "2" smd rect
			(at 0.5334 0)
			(size 0.7112 0.6096)
			(layers "F.Cu" "F.Mask" "F.Paste")
			(net "LM75B_I2C_SCL")
		)
		(zone
			(layer "F.Cu")
			(hatch none 0.5)
			(connect_pads
				(clearance 0)
			)
			(min_thickness 0.25)
			(keepout
				(tracks allowed)
				(vias not_allowed)
				(pads allowed)
				(copperpour not_allowed)
				(footprints allowed)
			)
			(placement
				(enabled no)
				(sheetname "")
			)
			(fill
				(thermal_gap 0.5)
				(thermal_bridge_width 0.5)
				(island_removal_mode 0)
			)
			(polygon
				(pts
					(xy 150.6728 -26.3398) (xy 150.6728 -25.7302) (xy 150.8252 -25.7302) (xy 150.8252 -26.3398)
				)
			)
		)
	)
	(footprint ""
		(layer "F.Cu")
		(at 80.772 -64.1096 180)
		(property "Reference" "C285"
			(at 10.287 19.29003 0)
			(unlocked yes)
			(layer "F.SilkS")
			(effects
				(font
					(size 0.7874 0.5842)
					(thickness 0.1524)
				)
			)
		)
		(property "Value" "VAL*"
			(at 0.0762 2.067306 180)
			(unlocked yes)
			(layer "F.Fab")
			(hide yes)
			(effects
				(font
					(size 0.7874 0.5842)
					(thickness 0.1524)
				)
			)
		)
		(property "Tolerance" "TOL*"
			(at 0.0762 3.032506 180)
			(unlocked yes)
			(layer "Cmts.User")
			(hide yes)
			(effects
				(font
					(size 0.7874 0.5842)
					(thickness 0.1524)
				)
			)
		)
		(property "User Part Number" "PARTNUM*"
			(at 0.1016 4.023106 180)
			(unlocked yes)
			(layer "Cmts.User")
			(hide yes)
			(effects
				(font
					(size 0.7874 0.5842)
					(thickness 0.1524)
				)
			)
		)
		(property "Device Type" "CAPACITOR-G105-0B104-CK,0.1UF,A"
			(at 0.0508 1.127506 180)
			(unlocked yes)
			(layer "F.Fab")
			(hide yes)
			(effects
				(font
					(size 0.7874 0.5842)
					(thickness 0.1524)
				)
			)
		)
		(duplicate_pad_numbers_are_jumpers no)
		(fp_line
			(start 1.143 0.5588)
			(end 1.143 -0.5588)
			(stroke
				(width 0.1)
				(type default)
			)
			(layer "F.SilkS")
		)
		(fp_line
			(start 1.143 -0.5588)
			(end -1.143 -0.5588)
			(stroke
				(width 0.1)
				(type default)
			)
			(layer "F.SilkS")
		)
		(fp_line
			(start -1.143 0.5588)
			(end 1.143 0.5588)
			(stroke
				(width 0.1)
				(type default)
			)
			(layer "F.SilkS")
		)
		(fp_line
			(start -1.143 -0.5588)
			(end -1.143 0.5588)
			(stroke
				(width 0.1)
				(type default)
			)
			(layer "F.SilkS")
		)
		(fp_rect
			(start 1.143 -0.5588)
			(end -1.143 0.5588)
			(stroke
				(width 0)
				(type default)
			)
			(fill no)
			(layer "F.CrtYd")
		)
		(fp_line
			(start 0.508 0.3048)
			(end 0.508 -0.3048)
			(stroke
				(width 0.1)
				(type default)
			)
			(layer "F.Fab")
		)
		(fp_line
			(start 0.508 -0.3048)
			(end -0.508 -0.3048)
			(stroke
				(width 0.1)
				(type default)
			)
			(layer "F.Fab")
		)
		(fp_line
			(start -0.508 0.3048)
			(end 0.508 0.3048)
			(stroke
				(width 0.1)
				(type default)
			)
			(layer "F.Fab")
		)
		(fp_line
			(start -0.508 -0.3048)
			(end -0.508 0.3048)
			(stroke
				(width 0.1)
				(type default)
			)
			(layer "F.Fab")
		)
		(pad "1" smd rect
			(at -0.5334 0 180)
			(size 0.7112 0.6096)
			(layers "F.Cu" "F.Mask" "F.Paste")
			(net "UNNAMED_9_BNO080LGA28_I29_CAP")
		)
		(pad "2" smd rect
			(at 0.5334 0 180)
			(size 0.7112 0.6096)
			(layers "F.Cu" "F.Mask" "F.Paste")
			(net "SG")
		)
		(zone
			(layer "F.Cu")
			(hatch none 0.5)
			(connect_pads
				(clearance 0)
			)
			(min_thickness 0.25)
			(keepout
				(tracks allowed)
				(vias not_allowed)
				(pads allowed)
				(copperpour not_allowed)
				(footprints allowed)
			)
			(placement
				(enabled no)
				(sheetname "")
			)
			(fill
				(thermal_gap 0.5)
				(thermal_bridge_width 0.5)
				(island_removal_mode 0)
			)
			(polygon
				(pts
					(xy 80.6958 -63.8048) (xy 80.8482 -63.8048) (xy 80.8482 -64.4144) (xy 80.6958 -64.4144)
				)
			)
		)
	)
)
